(kicad_pcb
	(version 20260206)
	(generator "pcbnew")
	(generator_version "10.0")
	(general
		(thickness 1.6)
		(legacy_teardrops no)
	)
	(paper "A4")
	(title_block
		(title "12092022_DA0F0TMDCD0_F0T_Management_Board_D_brd_V3_OCP.brd")
		(comment 1 "Grand Teton / footprints 1320-1325 of 1440")
	)
	(layers
		(0 "F.Cu" signal "TOP")
		(4 "In1.Cu" signal "GND")
		(6 "In2.Cu" signal "IN1")
		(8 "In3.Cu" signal "GND1")
		(10 "In4.Cu" signal "IN2")
		(12 "In5.Cu" signal "VCC")
		(14 "In6.Cu" signal "VCC1")
		(16 "In7.Cu" signal "IN3")
		(18 "In8.Cu" signal "GND2")
		(20 "In9.Cu" signal "IN4")
		(22 "In10.Cu" signal "GND3")
		(2 "B.Cu" signal "BOTTOM")
		(9 "F.Adhes" user "F.Adhesive")
		(11 "B.Adhes" user "B.Adhesive")
		(13 "F.Paste" user "Package Geometry/Pastemask Top")
		(15 "B.Paste" user "Package Geometry/Pastemask Bottom")
		(5 "F.SilkS" user "Ref Des/Silkscreen Top")
		(7 "B.SilkS" user "Ref Des/Silkscreen Bottom")
		(1 "F.Mask" user "Board Geometry/Soldermask Top")
		(3 "B.Mask" user "Board Geometry/Soldermask Bottom")
		(17 "Dwgs.User" user "User.Drawings")
		(19 "Cmts.User" user "User.Comments")
		(21 "Eco1.User" user "User.Eco1")
		(23 "Eco2.User" user "User.Eco2")
		(25 "Edge.Cuts" user "Board Geometry/Outline")
		(27 "Margin" user)
		(31 "F.CrtYd" user "Package Geometry/Place Bound Top")
		(29 "B.CrtYd" user "Package Geometry/Place Bound Bottom")
		(35 "F.Fab" user "Ref Des/Assembly Top")
		(33 "B.Fab" user "Ref Des/Assembly Bottom")
	)
	(footprint ""
		(layer "B.Cu")
		(at 15.548864 -58.7502 -90)
		(property "Reference" "R294"
			(at 0 0 90)
			(layer "B.SilkS")
			(hide yes)
			(effects
				(font
					(size 1.27 1.27)
				)
				(justify mirror)
			)
		)
		(property "Value" ""
			(at 0 0 90)
			(layer "B.Fab")
			(effects
				(font
					(size 1.27 1.27)
				)
				(justify mirror)
			)
		)
		(duplicate_pad_numbers_are_jumpers no)
		(fp_line
			(start -0.7874 0.4064)
			(end 0.7874 0.4064)
			(stroke
				(width 0.1524)
				(type default)
			)
			(layer "B.SilkS")
		)
		(fp_line
			(start 0.7874 0.4064)
			(end 0.7874 -0.4064)
			(stroke
				(width 0.1524)
				(type default)
			)
			(layer "B.SilkS")
		)
		(fp_line
			(start -0.7874 -0.4064)
			(end -0.7874 0.4064)
			(stroke
				(width 0.1524)
				(type default)
			)
			(layer "B.SilkS")
		)
		(fp_line
			(start 0.7874 -0.4064)
			(end -0.7874 -0.4064)
			(stroke
				(width 0.1524)
				(type default)
			)
			(layer "B.SilkS")
		)
		(fp_line
			(start -0.67945 0.3048)
			(end -0.120396 0.3048)
			(stroke
				(width 0.1)
				(type default)
			)
			(layer "B.Fab")
		)
		(fp_line
			(start -0.120396 0.3048)
			(end -0.120396 0.2794)
			(stroke
				(width 0.1)
				(type default)
			)
			(layer "B.Fab")
		)
		(fp_line
			(start 0.12065 0.3048)
			(end 0.67945 0.3048)
			(stroke
				(width 0.1)
				(type default)
			)
			(layer "B.Fab")
		)
		(fp_line
			(start 0.67945 0.3048)
			(end 0.67945 -0.305054)
			(stroke
				(width 0.1)
				(type default)
			)
			(layer "B.Fab")
		)
		(fp_line
			(start -0.120396 0.2794)
			(end 0.12065 0.2794)
			(stroke
				(width 0.1)
				(type default)
			)
			(layer "B.Fab")
		)
		(fp_line
			(start 0.12065 0.2794)
			(end 0.12065 0.3048)
			(stroke
				(width 0.1)
				(type default)
			)
			(layer "B.Fab")
		)
		(fp_line
			(start -0.12065 -0.2794)
			(end -0.12065 -0.3048)
			(stroke
				(width 0.1)
				(type default)
			)
			(layer "B.Fab")
		)
		(fp_line
			(start 0.12065 -0.2794)
			(end -0.12065 -0.2794)
			(stroke
				(width 0.1)
				(type default)
			)
			(layer "B.Fab")
		)
		(fp_line
			(start -0.67945 -0.3048)
			(end -0.67945 0.3048)
			(stroke
				(width 0.1)
				(type default)
			)
			(layer "B.Fab")
		)
		(fp_line
			(start -0.12065 -0.3048)
			(end -0.67945 -0.3048)
			(stroke
				(width 0.1)
				(type default)
			)
			(layer "B.Fab")
		)
		(fp_line
			(start 0.12065 -0.305054)
			(end 0.12065 -0.2794)
			(stroke
				(width 0.1)
				(type default)
			)
			(layer "B.Fab")
		)
		(fp_line
			(start 0.67945 -0.305054)
			(end 0.12065 -0.305054)
			(stroke
				(width 0.1)
				(type default)
			)
			(layer "B.Fab")
		)
		(pad "1" smd circle
			(at 0.40005 0 90)
			(size 0 0)
			(layers "B.Cu" "B.Mask" "B.Paste")
			(net "SMB_BMC_MM15_SDA")
		)
		(pad "2" smd circle
			(at -0.40005 0 90)
			(size 0 0)
			(layers "B.Cu" "B.Mask" "B.Paste")
			(net "SMB_BMC_MM15_R1_SDA")
		)
	)
	(footprint ""
		(layer "B.Cu")
		(at 47.85487 -71.92137 180)
		(property "Reference" "R778"
			(at 0 0 0)
			(layer "B.SilkS")
			(hide yes)
			(effects
				(font
					(size 1.27 1.27)
				)
				(justify mirror)
			)
		)
		(property "Value" ""
			(at 0 0 0)
			(layer "B.Fab")
			(effects
				(font
					(size 1.27 1.27)
				)
				(justify mirror)
			)
		)
		(duplicate_pad_numbers_are_jumpers no)
		(fp_line
			(start 0.7874 0.4064)
			(end 0.7874 -0.4064)
			(stroke
				(width 0.1524)
				(type default)
			)
			(layer "B.SilkS")
		)
		(fp_line
			(start 0.7874 -0.4064)
			(end -0.7874 -0.4064)
			(stroke
				(width 0.1524)
				(type default)
			)
			(layer "B.SilkS")
		)
		(fp_line
			(start -0.7874 0.4064)
			(end 0.7874 0.4064)
			(stroke
				(width 0.1524)
				(type default)
			)
			(layer "B.SilkS")
		)
		(fp_line
			(start -0.7874 -0.4064)
			(end -0.7874 0.4064)
			(stroke
				(width 0.1524)
				(type default)
			)
			(layer "B.SilkS")
		)
		(fp_line
			(start 0.67945 0.3048)
			(end 0.67945 -0.305054)
			(stroke
				(width 0.1)
				(type default)
			)
			(layer "B.Fab")
		)
		(fp_line
			(start 0.67945 -0.305054)
			(end 0.12065 -0.305054)
			(stroke
				(width 0.1)
				(type default)
			)
			(layer "B.Fab")
		)
		(fp_line
			(start 0.12065 0.3048)
			(end 0.67945 0.3048)
			(stroke
				(width 0.1)
				(type default)
			)
			(layer "B.Fab")
		)
		(fp_line
			(start 0.12065 0.2794)
			(end 0.12065 0.3048)
			(stroke
				(width 0.1)
				(type default)
			)
			(layer "B.Fab")
		)
		(fp_line
			(start 0.12065 -0.2794)
			(end -0.12065 -0.2794)
			(stroke
				(width 0.1)
				(type default)
			)
			(layer "B.Fab")
		)
		(fp_line
			(start 0.12065 -0.305054)
			(end 0.12065 -0.2794)
			(stroke
				(width 0.1)
				(type default)
			)
			(layer "B.Fab")
		)
		(fp_line
			(start -0.120396 0.3048)
			(end -0.120396 0.2794)
			(stroke
				(width 0.1)
				(type default)
			)
			(layer "B.Fab")
		)
		(fp_line
			(start -0.120396 0.2794)
			(end 0.12065 0.2794)
			(stroke
				(width 0.1)
				(type default)
			)
			(layer "B.Fab")
		)
		(fp_line
			(start -0.12065 -0.2794)
			(end -0.12065 -0.3048)
			(stroke
				(width 0.1)
				(type default)
			)
			(layer "B.Fab")
		)
		(fp_line
			(start -0.12065 -0.3048)
			(end -0.67945 -0.3048)
			(stroke
				(width 0.1)
				(type default)
			)
			(layer "B.Fab")
		)
		(fp_line
			(start -0.67945 0.3048)
			(end -0.120396 0.3048)
			(stroke
				(width 0.1)
				(type default)
			)
			(layer "B.Fab")
		)
		(fp_line
			(start -0.67945 -0.3048)
			(end -0.67945 0.3048)
			(stroke
				(width 0.1)
				(type default)
			)
			(layer "B.Fab")
		)
		(pad "1" smd circle
			(at 0.40005 0)
			(size 0 0)
			(layers "B.Cu" "B.Mask" "B.Paste")
			(net "P3V_BAT_SENSOR")
		)
		(pad "2" smd circle
			(at -0.40005 0)
			(size 0 0)
			(layers "B.Cu" "B.Mask" "B.Paste")
			(net "GND")
		)
	)
	(footprint ""
		(layer "B.Cu")
		(at 45.085 -62.0014 -90)
		(property "Reference" "R24"
			(at 0 0 90)
			(layer "B.SilkS")
			(hide yes)
			(effects
				(font
					(size 1.27 1.27)
				)
				(justify mirror)
			)
		)
		(property "Value" ""
			(at 0 0 90)
			(layer "B.Fab")
			(effects
				(font
					(size 1.27 1.27)
				)
				(justify mirror)
			)
		)
		(duplicate_pad_numbers_are_jumpers no)
		(fp_line
			(start -0.7874 0.4064)
			(end 0.7874 0.4064)
			(stroke
				(width 0.1524)
				(type default)
			)
			(layer "B.SilkS")
		)
		(fp_line
			(start 0.7874 0.4064)
			(end 0.7874 -0.4064)
			(stroke
				(width 0.1524)
				(type default)
			)
			(layer "B.SilkS")
		)
		(fp_line
			(start -0.7874 -0.4064)
			(end -0.7874 0.4064)
			(stroke
				(width 0.1524)
				(type default)
			)
			(layer "B.SilkS")
		)
		(fp_line
			(start 0.7874 -0.4064)
			(end -0.7874 -0.4064)
			(stroke
				(width 0.1524)
				(type default)
			)
			(layer "B.SilkS")
		)
		(fp_line
			(start -0.67945 0.3048)
			(end -0.120396 0.3048)
			(stroke
				(width 0.1)
				(type default)
			)
			(layer "B.Fab")
		)
		(fp_line
			(start -0.120396 0.3048)
			(end -0.120396 0.2794)
			(stroke
				(width 0.1)
				(type default)
			)
			(layer "B.Fab")
		)
		(fp_line
			(start 0.12065 0.3048)
			(end 0.67945 0.3048)
			(stroke
				(width 0.1)
				(type default)
			)
			(layer "B.Fab")
		)
		(fp_line
			(start 0.67945 0.3048)
			(end 0.67945 -0.305054)
			(stroke
				(width 0.1)
				(type default)
			)
			(layer "B.Fab")
		)
		(fp_line
			(start -0.120396 0.2794)
			(end 0.12065 0.2794)
			(stroke
				(width 0.1)
				(type default)
			)
			(layer "B.Fab")
		)
		(fp_line
			(start 0.12065 0.2794)
			(end 0.12065 0.3048)
			(stroke
				(width 0.1)
				(type default)
			)
			(layer "B.Fab")
		)
		(fp_line
			(start -0.12065 -0.2794)
			(end -0.12065 -0.3048)
			(stroke
				(width 0.1)
				(type default)
			)
			(layer "B.Fab")
		)
		(fp_line
			(start 0.12065 -0.2794)
			(end -0.12065 -0.2794)
			(stroke
				(width 0.1)
				(type default)
			)
			(layer "B.Fab")
		)
		(fp_line
			(start -0.67945 -0.3048)
			(end -0.67945 0.3048)
			(stroke
				(width 0.1)
				(type default)
			)
			(layer "B.Fab")
		)
		(fp_line
			(start -0.12065 -0.3048)
			(end -0.67945 -0.3048)
			(stroke
				(width 0.1)
				(type default)
			)
			(layer "B.Fab")
		)
		(fp_line
			(start 0.12065 -0.305054)
			(end 0.12065 -0.2794)
			(stroke
				(width 0.1)
				(type default)
			)
			(layer "B.Fab")
		)
		(fp_line
			(start 0.67945 -0.305054)
			(end 0.12065 -0.305054)
			(stroke
				(width 0.1)
				(type default)
			)
			(layer "B.Fab")
		)
		(pad "1" smd circle
			(at 0.40005 0 90)
			(size 0 0)
			(layers "B.Cu" "B.Mask" "B.Paste")
			(net "V_DACB_R")
		)
		(pad "2" smd circle
			(at -0.40005 0 90)
			(size 0 0)
			(layers "B.Cu" "B.Mask" "B.Paste")
			(net "V_DACB")
		)
	)
	(footprint ""
		(layer "B.Cu")
		(at 31.027624 -37.5412 90)
		(property "Reference" "D11"
			(at -3.7592 -3.977894 270)
			(unlocked yes)
			(layer "B.SilkS")
			(effects
				(font
					(size 0.7874 0.5842)
					(thickness 0.1524)
				)
				(justify left mirror)
			)
		)
		(property "Value" ""
			(at 0 0 90)
			(layer "B.Fab")
			(effects
				(font
					(size 1.27 1.27)
				)
				(justify mirror)
			)
		)
		(duplicate_pad_numbers_are_jumpers no)
		(fp_line
			(start 2.262378 -0.899922)
			(end 2.262378 0.899922)
			(stroke
				(width 0.1524)
				(type default)
			)
			(layer "B.SilkS")
		)
		(fp_line
			(start -2.567178 -0.899922)
			(end 2.262378 -0.899922)
			(stroke
				(width 0.1524)
				(type default)
			)
			(layer "B.SilkS")
		)
		(fp_line
			(start 0.3175 -0.508)
			(end 0.3175 0.508)
			(stroke
				(width 0.1524)
				(type default)
			)
			(layer "B.SilkS")
		)
		(fp_line
			(start -0.3175 -0.508)
			(end -0.3175 0.508)
			(stroke
				(width 0.1524)
				(type default)
			)
			(layer "B.SilkS")
		)
		(fp_line
			(start 0.8255 0)
			(end 0.3175 0)
			(stroke
				(width 0.1524)
				(type default)
			)
			(layer "B.SilkS")
		)
		(fp_line
			(start -0.3175 0)
			(end 0.3175 -0.508)
			(stroke
				(width 0.1524)
				(type default)
			)
			(layer "B.SilkS")
		)
		(fp_line
			(start -0.3175 0)
			(end -0.8255 0)
			(stroke
				(width 0.1524)
				(type default)
			)
			(layer "B.SilkS")
		)
		(fp_line
			(start 0.3175 0.508)
			(end -0.3175 0)
			(stroke
				(width 0.1524)
				(type default)
			)
			(layer "B.SilkS")
		)
		(fp_line
			(start 2.262378 0.899922)
			(end -2.567178 0.899922)
			(stroke
				(width 0.1524)
				(type default)
			)
			(layer "B.SilkS")
		)
		(fp_line
			(start -2.567178 0.899922)
			(end -2.567178 -0.899922)
			(stroke
				(width 0.1524)
				(type default)
			)
			(layer "B.SilkS")
		)
		(fp_poly
			(pts
				(xy -2.567178 -0.899922) (xy -2.186178 -0.899922) (xy -2.186178 0.899922) (xy -2.567178 0.899922)
			)
			(stroke
				(width 0)
				(type default)
			)
			(fill yes)
			(layer "B.SilkS")
		)
		(fp_line
			(start 1.400048 -0.899922)
			(end 1.400048 0.899922)
			(stroke
				(width 0.1)
				(type default)
			)
			(layer "B.Fab")
		)
		(fp_line
			(start -1.400048 -0.899922)
			(end 1.400048 -0.899922)
			(stroke
				(width 0.1)
				(type default)
			)
			(layer "B.Fab")
		)
		(fp_line
			(start 1.400048 0.899922)
			(end -1.400048 0.899922)
			(stroke
				(width 0.1)
				(type default)
			)
			(layer "B.Fab")
		)
		(fp_line
			(start -1.400048 0.899922)
			(end -1.400048 -0.899922)
			(stroke
				(width 0.1)
				(type default)
			)
			(layer "B.Fab")
		)
		(fp_text user "+"
			(at 1.938274 -0.618236 270)
			(unlocked yes)
			(layer "B.SilkS")
			(effects
				(font
					(size 1.905 1.4224)
					(thickness 0.1524)
				)
				(justify left mirror)
			)
		)
		(fp_text user "-"
			(at -3.937762 0.241046 270)
			(unlocked yes)
			(layer "B.SilkS")
			(effects
				(font
					(size 1.905 1.4224)
					(thickness 0.1524)
				)
				(justify left mirror)
			)
		)
		(fp_text user "-"
			(at -3.937762 0.241046 270)
			(unlocked yes)
			(layer "B.Fab")
			(effects
				(font
					(size 1.905 1.4224)
					(thickness 0.1524)
				)
				(justify left mirror)
			)
		)
		(fp_text user "+"
			(at 3.29565 0.6858 0)
			(unlocked yes)
			(layer "B.Fab")
			(effects
				(font
					(size 1.905 1.4224)
					(thickness 0.1524)
				)
				(justify left mirror)
			)
		)
		(pad "A" smd rect
			(at 1.640078 0 270)
			(size 0.9906 1.2192)
			(layers "B.Cu" "B.Mask" "B.Paste")
			(net "P5V_AUX")
		)
		(pad "C" smd rect
			(at -1.640078 0 270)
			(size 0.9906 1.2192)
			(layers "B.Cu" "B.Mask" "B.Paste")
			(net "CRT_VCC5")
		)
	)
	(footprint ""
		(layer "B.Cu")
		(at 81.161636 -38.957758 180)
		(property "Reference" "R370"
			(at 0 0 0)
			(layer "B.SilkS")
			(hide yes)
			(effects
				(font
					(size 1.27 1.27)
				)
				(justify mirror)
			)
		)
		(property "Value" ""
			(at 0 0 0)
			(layer "B.Fab")
			(effects
				(font
					(size 1.27 1.27)
				)
				(justify mirror)
			)
		)
		(duplicate_pad_numbers_are_jumpers no)
		(fp_line
			(start 0.7874 0.4064)
			(end 0.7874 -0.4064)
			(stroke
				(width 0.1524)
				(type default)
			)
			(layer "B.SilkS")
		)
		(fp_line
			(start 0.7874 -0.4064)
			(end -0.7874 -0.4064)
			(stroke
				(width 0.1524)
				(type default)
			)
			(layer "B.SilkS")
		)
		(fp_line
			(start -0.7874 0.4064)
			(end 0.7874 0.4064)
			(stroke
				(width 0.1524)
				(type default)
			)
			(layer "B.SilkS")
		)
		(fp_line
			(start -0.7874 -0.4064)
			(end -0.7874 0.4064)
			(stroke
				(width 0.1524)
				(type default)
			)
			(layer "B.SilkS")
		)
		(fp_line
			(start 0.67945 0.3048)
			(end 0.67945 -0.305054)
			(stroke
				(width 0.1)
				(type default)
			)
			(layer "B.Fab")
		)
		(fp_line
			(start 0.67945 -0.305054)
			(end 0.12065 -0.305054)
			(stroke
				(width 0.1)
				(type default)
			)
			(layer "B.Fab")
		)
		(fp_line
			(start 0.12065 0.3048)
			(end 0.67945 0.3048)
			(stroke
				(width 0.1)
				(type default)
			)
			(layer "B.Fab")
		)
		(fp_line
			(start 0.12065 0.2794)
			(end 0.12065 0.3048)
			(stroke
				(width 0.1)
				(type default)
			)
			(layer "B.Fab")
		)
		(fp_line
			(start 0.12065 -0.2794)
			(end -0.12065 -0.2794)
			(stroke
				(width 0.1)
				(type default)
			)
			(layer "B.Fab")
		)
		(fp_line
			(start 0.12065 -0.305054)
			(end 0.12065 -0.2794)
			(stroke
				(width 0.1)
				(type default)
			)
			(layer "B.Fab")
		)
		(fp_line
			(start -0.120396 0.3048)
			(end -0.120396 0.2794)
			(stroke
				(width 0.1)
				(type default)
			)
			(layer "B.Fab")
		)
		(fp_line
			(start -0.120396 0.2794)
			(end 0.12065 0.2794)
			(stroke
				(width 0.1)
				(type default)
			)
			(layer "B.Fab")
		)
		(fp_line
			(start -0.12065 -0.2794)
			(end -0.12065 -0.3048)
			(stroke
				(width 0.1)
				(type default)
			)
			(layer "B.Fab")
		)
		(fp_line
			(start -0.12065 -0.3048)
			(end -0.67945 -0.3048)
			(stroke
				(width 0.1)
				(type default)
			)
			(layer "B.Fab")
		)
		(fp_line
			(start -0.67945 0.3048)
			(end -0.120396 0.3048)
			(stroke
				(width 0.1)
				(type default)
			)
			(layer "B.Fab")
		)
		(fp_line
			(start -0.67945 -0.3048)
			(end -0.67945 0.3048)
			(stroke
				(width 0.1)
				(type default)
			)
			(layer "B.Fab")
		)
		(pad "1" smd circle
			(at 0.40005 0)
			(size 0 0)
			(layers "B.Cu" "B.Mask" "B.Paste")
			(net "M_BMC_DDR4_MBG0")
		)
		(pad "2" smd circle
			(at -0.40005 0)
			(size 0 0)
			(layers "B.Cu" "B.Mask" "B.Paste")
			(net "P1V2_AUX")
		)
	)
	(footprint ""
		(layer "B.Cu")
		(at 54.313582 -68.349368 90)
		(property "Reference" "R792"
			(at 0 0 90)
			(layer "B.SilkS")
			(hide yes)
			(effects
				(font
					(size 1.27 1.27)
				)
				(justify mirror)
			)
		)
		(property "Value" ""
			(at 0 0 90)
			(layer "B.Fab")
			(effects
				(font
					(size 1.27 1.27)
				)
				(justify mirror)
			)
		)
		(duplicate_pad_numbers_are_jumpers no)
		(fp_line
			(start 0.7874 -0.4064)
			(end -0.7874 -0.4064)
			(stroke
				(width 0.1524)
				(type default)
			)
			(layer "B.SilkS")
		)
		(fp_line
			(start -0.7874 -0.4064)
			(end -0.7874 0.4064)
			(stroke
				(width 0.1524)
				(type default)
			)
			(layer "B.SilkS")
		)
		(fp_line
			(start 0.7874 0.4064)
			(end 0.7874 -0.4064)
			(stroke
				(width 0.1524)
				(type default)
			)
			(layer "B.SilkS")
		)
		(fp_line
			(start -0.7874 0.4064)
			(end 0.7874 0.4064)
			(stroke
				(width 0.1524)
				(type default)
			)
			(layer "B.SilkS")
		)
		(fp_line
			(start 0.67945 -0.305054)
			(end 0.12065 -0.305054)
			(stroke
				(width 0.1)
				(type default)
			)
			(layer "B.Fab")
		)
		(fp_line
			(start 0.12065 -0.305054)
			(end 0.12065 -0.2794)
			(stroke
				(width 0.1)
				(type default)
			)
			(layer "B.Fab")
		)
		(fp_line
			(start -0.12065 -0.3048)
			(end -0.67945 -0.3048)
			(stroke
				(width 0.1)
				(type default)
			)
			(layer "B.Fab")
		)
		(fp_line
			(start -0.67945 -0.3048)
			(end -0.67945 0.3048)
			(stroke
				(width 0.1)
				(type default)
			)
			(layer "B.Fab")
		)
		(fp_line
			(start 0.12065 -0.2794)
			(end -0.12065 -0.2794)
			(stroke
				(width 0.1)
				(type default)
			)
			(layer "B.Fab")
		)
		(fp_line
			(start -0.12065 -0.2794)
			(end -0.12065 -0.3048)
			(stroke
				(width 0.1)
				(type default)
			)
			(layer "B.Fab")
		)
		(fp_line
			(start 0.12065 0.2794)
			(end 0.12065 0.3048)
			(stroke
				(width 0.1)
				(type default)
			)
			(layer "B.Fab")
		)
		(fp_line
			(start -0.120396 0.2794)
			(end 0.12065 0.2794)
			(stroke
				(width 0.1)
				(type default)
			)
			(layer "B.Fab")
		)
		(fp_line
			(start 0.67945 0.3048)
			(end 0.67945 -0.305054)
			(stroke
				(width 0.1)
				(type default)
			)
			(layer "B.Fab")
		)
		(fp_line
			(start 0.12065 0.3048)
			(end 0.67945 0.3048)
			(stroke
				(width 0.1)
				(type default)
			)
			(layer "B.Fab")
		)
		(fp_line
			(start -0.120396 0.3048)
			(end -0.120396 0.2794)
			(stroke
				(width 0.1)
				(type default)
			)
			(layer "B.Fab")
		)
		(fp_line
			(start -0.67945 0.3048)
			(end -0.120396 0.3048)
			(stroke
				(width 0.1)
				(type default)
			)
			(layer "B.Fab")
		)
		(pad "1" smd circle
			(at 0.40005 0 270)
			(size 0 0)
			(layers "B.Cu" "B.Mask" "B.Paste")
			(net "P2V5_SENSOR")
		)
		(pad "2" smd circle
			(at -0.40005 0 270)
			(size 0 0)
			(layers "B.Cu" "B.Mask" "B.Paste")
			(net "GND")
		)
	)
)
